# discovery-power-board-v1-revB — FixingPoint_Plated_Hole_D4.0mm.kicad_mod (kicad-footprint)
(module FixingPoint_Plated_Hole_D4.0mm (layer F.Cu) 
  (descr "Plated Hole as fixing Point, diameter 4.0mm")
  (tags "fixing point plated hole")
  (attr virtual)
  (fp_text reference W2 (at 3.81878 2.29224) (layer F.SilkS)
    (effects (font (size 1 1) (thickness 0.15)))
  )
  (fp_text value "Fixing hole" (at 0 3.55) (layer F.Fab)
    (effects (font (size 1 1) (thickness 0.15)))
  )
  (fp_circle (center 0 0) (end 0 2.75) (layer F.SilkS) (width 0.12))
  (fp_circle (center 0 0) (end 3 0) (layer F.CrtYd) (width 0.05))
  (fp_text user %R (at 0 -3.55) (layer F.Fab)
    (effects (font (size 1 1) (thickness 0.15)))
  )
  (pad 1 thru_hole circle (at 0 0) (size 5 5) (drill 4) (layers *.Cu *.Mask))
)
